FILE_TYPE = MACRO_DRAWING;
SET COLOR_WIRE YELLOW;
SET COLOR_PROP ORANGE;
SET COLOR_DOT WHITE;
SET COLOR_ARC YELLOW;
SET COLOR_BODY GREEN;
SET COLOR_NOTE PURPLE;
SET PROP_DISPLAY VALUE;
SET PAGE_NUMBER P423;
FORCEADD QUANTA_TITLE_BLOCK_C..1
(0 0);
FORCEPROP 1 LAST CUSTOM_TXT_CDS <NAME_2>
J 0
(-3175 50);
FORCEPROP 1 LAST CUSTOM_TXT_CDS <NAME_1>
J 0
(-3175 175);
FORCEPROP 1 LAST CUSTOM_TXT_CDS <Q_NUMBER>
J 0
(-1403 103);
DISPLAY 1.212766 (-1403 103);
FORCEPROP 1 LAST CUSTOM_TXT_CDS <Q_PROJ>
J 0
(-2382 102);
DISPLAY 1.212766 (-2382 102);
FORCEPROP 1 LAST CUSTOM_TXT_CDS <Q_REV>
J 0
(-184 103);
DISPLAY 1.212766 (-184 103);
FORCEPROP 1 LAST CUSTOM_TXT_CDS <CON_LAST_MODIFIED>
J 0
(-1885 15);
DISPLAY 0.978723 (-1885 15);
FORCEPROP 1 LAST CUSTOM_TXT_CDS <CON_PAGE_NUM> OF <CON_TOTAL_PAGES>
J 0
(-446 18);
DISPLAY 0.978723 (-446 18);
FORCEPROP 1 LAST Q_TITLE RETIMER_CPU0_P2(9)
J 0
(-9366 26);
DISPLAY 2.446809 (-9366 26);
PAINT GREEN (-9366 26);
FORCEPROP 2 LAST CDS_LIB pure_quanta
J 0
(0 0);
DISPLAY INVISIBLE (0 0);
FORCEPROP 1 LAST CDS_LMAN_SYM_OUTLINE -9475,6775,100,-125
J 0
(0 0);
DISPLAY 0.468085 (0 0);
PAINT GREEN (0 0);
DISPLAY INVISIBLE (0 0);
FORCEPROP 2 LAST PAGE_BORDER TRUE
J 0
(-7890 5250);
DISPLAY 0.638298 (-7890 5250);
PAINT PINK (-7890 5250);
DISPLAY INVISIBLE (-7890 5250);
FORCEPROP 2 LAST CDS_XR_PAGE_TITLE CR-303 : @T6G_MB_LIB.T6G(SCH_1):PAGE303
J 0
(-7890 5250);
DISPLAY 0.638298 (-7890 5250);
PAINT PINK (-7890 5250);
DISPLAY INVISIBLE (-7890 5250);
FORCEPROP 2 LAST CUSTOM_TXT_CDS <XR_PAGE_TITLE>
J 0
(-7890 5250);
DISPLAY 0.638298 (-7890 5250);
PAINT PINK (-7890 5250);
DISPLAY INVISIBLE (-7890 5250);
FORCEPROP 1 LAST COMMENT_BODY TRUE
J 0
(12 -13);
DISPLAY 0.978723 (12 -13);
PAINT GREEN (12 -13);
DISPLAY INVISIBLE (12 -13);
FORCEPROP 1 LAST Q_DEPT BU9
J 1
(-3763 49);
DISPLAY 1.957447 (-3763 49);
PAINT GREEN (-3763 49);
DISPLAY INVISIBLE (-3763 49);
FORCEPROP 0 LAST CDS_CON_LAST_MODIFIED Thu Aug 24 10:16:26 2023
J 0
(-1885 15);
DISPLAY INVISIBLE (-1885 15);
QUIT
